(kicad_pcb
	(version 20241229)
	(generator "pcbnew")
	(generator_version "9.0")
	(general
		(thickness 1.6642)
		(legacy_teardrops no)
	)
	(paper "A3")
	(title_block
		(title "PolarFire SoM")
		(date "2025-07-22")
		(rev "1.1.4")
		(company "Antmicro Ltd")
		(comment 1 "www.antmicro.com")
		(comment 9 "footprint 85 of 470 (U1), pads 206-282 of 484")
	)
	(layers
		(0 "F.Cu" mixed)
		(4 "In1.Cu" power)
		(6 "In2.Cu" signal)
		(8 "In3.Cu" power)
		(10 "In4.Cu" signal)
		(12 "In5.Cu" power)
		(14 "In6.Cu" power)
		(16 "In7.Cu" signal)
		(18 "In8.Cu" power)
		(20 "In9.Cu" signal)
		(22 "In10.Cu" power)
		(24 "In11.Cu" signal)
		(26 "In12.Cu" signal)
		(2 "B.Cu" mixed)
		(9 "F.Adhes" user "F.Adhesive")
		(11 "B.Adhes" user "B.Adhesive")
		(13 "F.Paste" user)
		(15 "B.Paste" user)
		(5 "F.SilkS" user "F.Silkscreen")
		(7 "B.SilkS" user "B.Silkscreen")
		(1 "F.Mask" user)
		(3 "B.Mask" user)
		(17 "Dwgs.User" user "User.Drawings")
		(19 "Cmts.User" user "User.Comments")
		(21 "Eco1.User" user "User.Eco1")
		(23 "Eco2.User" user "User.Eco2")
		(25 "Edge.Cuts" user)
		(27 "Margin" user)
		(31 "F.CrtYd" user "F.Courtyard")
		(29 "B.CrtYd" user "B.Courtyard")
		(35 "F.Fab" user)
		(33 "B.Fab" user)
	)
	(footprint "antmicro-footprints:BGA-484_19x19mm_Layout22x22_P0.8mm_FCVG484"
		(layer "F.Cu")
		(at 197.699 132.701 -90)
		(descr "FCVG484, 19.0x19.0mm, 484 Ball, 22x22 Layout, 0.8mm Pitch")
		(tags "BGA 484 0.8")
		(property "Reference" "U1"
			(at 0 -10.8 270)
			(layer "F.SilkS")
			(effects
				(font
					(size 0.7 0.7)
					(thickness 0.15)
				)
				(justify left bottom)
			)
		)
		(property "Value" "MPFS250T-FCVG484"
			(at 0 11.5 270)
			(layer "F.Fab")
			(hide yes)
			(effects
				(font
					(size 0.7 0.7)
					(thickness 0.15)
				)
				(justify left bottom)
			)
		)
		(property "Datasheet" "https://ww1.microchip.com/downloads/aemDocuments/documents/FPGA/ProductDocuments/DataSheets/PolarFire-SoC-Datasheet-DS00004248.pdf"
			(at 0 0 270)
			(layer "F.Fab")
			(hide yes)
			(effects
				(font
					(size 1.27 1.27)
					(thickness 0.15)
				)
			)
		)
		(property "Description" "RISC-V System On Chip (SOC) IC PolarFire® FPGA - 254K Logic Modules 484-FCBGA (19x19)"
			(at 0 0 270)
			(layer "F.Fab")
			(hide yes)
			(effects
				(font
					(size 1.27 1.27)
					(thickness 0.15)
				)
			)
		)
		(property "MPN" "MPFS250T-FCVG484E"
			(at 0 0 270)
			(unlocked yes)
			(layer "F.Fab")
			(hide yes)
			(effects
				(font
					(size 1 1)
					(thickness 0.15)
				)
			)
		)
		(property "Manufacturer" "Microchip Technology"
			(at 0 0 270)
			(unlocked yes)
			(layer "F.Fab")
			(hide yes)
			(effects
				(font
					(size 1 1)
					(thickness 0.15)
				)
			)
		)
		(property "VSD_class" "MPFS250T"
			(at 0 0 270)
			(unlocked yes)
			(layer "F.Fab")
			(hide yes)
			(effects
				(font
					(size 1 1)
					(thickness 0.15)
				)
			)
		)
		(property "Author" "Antmicro"
			(at 0 0 270)
			(unlocked yes)
			(layer "F.Fab")
			(hide yes)
			(effects
				(font
					(size 1 1)
					(thickness 0.15)
				)
			)
		)
		(property "License" "Apache-2.0"
			(at 0 0 270)
			(unlocked yes)
			(layer "F.Fab")
			(hide yes)
			(effects
				(font
					(size 1 1)
					(thickness 0.15)
				)
			)
		)
		(sheetname "/FPGA Config/")
		(sheetfile "fpga-config.kicad_sch")
		(attr smd)
		(pad "H8" smd circle
			(at -2.8 -2.8 270)
			(size 0.45 0.45)
			(layers "F.Cu" "F.Mask" "F.Paste")
			(net 418 "+2V5")
			(pinfunction "VDD25")
			(pintype "power_in")
		)
		(pad "H9" smd circle
			(at -2 -2.8 270)
			(size 0.45 0.45)
			(layers "F.Cu" "F.Mask" "F.Paste")
			(net 255 "Net-(U1D-IO_CFG_INTF)")
			(pinfunction "IO_CFG_INTF")
			(pintype "input")
			(die_length 6.79819)
		)
		(pad "H10" smd circle
			(at -1.2 -2.8 270)
			(size 0.45 0.45)
			(layers "F.Cu" "F.Mask" "F.Paste")
			(net 290 "/FPGA Config/Flash.MISO")
			(pinfunction "SDI")
			(pintype "input")
			(die_length 6.8817)
		)
		(pad "H11" smd circle
			(at -0.401 -2.8 270)
			(size 0.45 0.45)
			(layers "F.Cu" "F.Mask" "F.Paste")
			(net 256 "Net-(U1D-SPI_EN)")
			(pinfunction "SPI_EN")
			(pintype "input")
			(die_length 7.76583)
		)
		(pad "H12" smd circle
			(at 0.4 -2.8 270)
			(size 0.45 0.45)
			(layers "F.Cu" "F.Mask" "F.Paste")
			(net 31 "UART4_TX{slash}RPI_GPIO08")
			(pinfunction "GPIO182PB1/DQS")
			(pintype "bidirectional")
			(die_length 12.3884)
		)
		(pad "H13" smd circle
			(at 1.199 -2.8 270)
			(size 0.45 0.45)
			(layers "F.Cu" "F.Mask" "F.Paste")
			(net 17 "GPIO7")
			(pinfunction "GPIO185NB1")
			(pintype "bidirectional")
			(die_length 12.28)
		)
		(pad "H14" smd circle
			(at 1.999 -2.8 270)
			(size 0.45 0.45)
			(layers "F.Cu" "F.Mask" "F.Paste")
			(net 49 "VDDAUX")
			(pinfunction "VDDAUX1")
			(pintype "power_in")
		)
		(pad "H15" smd circle
			(at 2.799 -2.8 270)
			(size 0.45 0.45)
			(layers "F.Cu" "F.Mask" "F.Paste")
			(net 134 "UART0_RX{slash}RPI_GPIO15")
			(pinfunction "GPIO7NB1")
			(pintype "bidirectional")
			(die_length 10.5915)
		)
		(pad "H16" smd circle
			(at 3.6 -2.8 270)
			(size 0.45 0.45)
			(layers "F.Cu" "F.Mask" "F.Paste")
			(net 49 "VDDAUX")
			(pinfunction "VDDAUX1")
			(pintype "passive")
		)
		(pad "H17" smd circle
			(at 4.4 -2.8 270)
			(size 0.45 0.45)
			(layers "F.Cu" "F.Mask" "F.Paste")
			(net 28 "GPIO17")
			(pinfunction "GPIO8NB1/DQS")
			(pintype "bidirectional")
			(die_length 11.6441)
		)
		(pad "H18" smd circle
			(at 5.2 -2.8 270)
			(size 0.45 0.45)
			(layers "F.Cu" "F.Mask" "F.Paste")
			(net 1 "/FPGA Supply/XCVR_VREF")
			(pinfunction "XCVR_VREF")
			(pintype "power_in")
		)
		(pad "H19" smd circle
			(at 5.999 -2.8 270)
			(size 0.45 0.45)
			(layers "F.Cu" "F.Mask" "F.Paste")
			(net 1 "/FPGA Supply/XCVR_VREF")
			(pinfunction "XCVR_VREF")
			(pintype "passive")
		)
		(pad "H20" smd circle
			(at 6.799 -2.8 270)
			(size 0.45 0.45)
			(layers "F.Cu" "F.Mask" "F.Paste")
			(net 417 "GND")
			(pinfunction "VSS")
			(pintype "passive")
		)
		(pad "H21" smd circle
			(at 7.599 -2.8 270)
			(size 0.45 0.45)
			(layers "F.Cu" "F.Mask" "F.Paste")
			(net 46 "/PCIe/XCVR_TX1_N")
			(pinfunction "XCVR_0_TX1_N")
			(pintype "output")
			(die_length 7.41112)
		)
		(pad "H22" smd circle
			(at 8.4 -2.8 270)
			(size 0.45 0.45)
			(layers "F.Cu" "F.Mask" "F.Paste")
			(net 51 "/PCIe/XCVR_TX1_P")
			(pinfunction "XCVR_0_TX1_P")
			(pintype "output")
			(die_length 7.39947)
		)
		(pad "J1" smd circle
			(at -8.401 -2 270)
			(size 0.45 0.45)
			(layers "F.Cu" "F.Mask" "F.Paste")
			(net 265 "/FPGA MSSIO/MEM.CLK")
			(pinfunction "MSSIO0B4")
			(pintype "bidirectional")
			(die_length 7.51872)
		)
		(pad "J2" smd circle
			(at -7.6 -2 270)
			(size 0.45 0.45)
			(layers "F.Cu" "F.Mask" "F.Paste")
			(net 627 "unconnected-(U1E-MSSIO13B4-PadJ2)")
			(pinfunction "MSSIO13B4")
			(pintype "bidirectional+no_connect")
			(die_length 6.70124)
		)
		(pad "J3" smd circle
			(at -6.8 -2 270)
			(size 0.45 0.45)
			(layers "F.Cu" "F.Mask" "F.Paste")
			(net 252 "/FPGA MSSIO/MEM.DAT6")
			(pinfunction "MSSIO10B4")
			(pintype "bidirectional")
			(die_length 7.82186)
		)
		(pad "J4" smd circle
			(at -6 -2 270)
			(size 0.45 0.45)
			(layers "F.Cu" "F.Mask" "F.Paste")
			(net 262 "/FPGA MSSIO/MEM.DAT1")
			(pinfunction "MSSIO3B4")
			(pintype "bidirectional")
			(die_length 8.67867)
		)
		(pad "J5" smd circle
			(at -5.201 -2 270)
			(size 0.45 0.45)
			(layers "F.Cu" "F.Mask" "F.Paste")
			(net 137 "SD_VDD")
			(pinfunction "VDDI4")
			(pintype "power_in")
		)
		(pad "J6" smd circle
			(at -4.401 -2 270)
			(size 0.45 0.45)
			(layers "F.Cu" "F.Mask" "F.Paste")
			(net 251 "/FPGA MSSIO/MEM.DAT4")
			(pinfunction "MSSIO8B4")
			(pintype "bidirectional")
			(die_length 9.38542)
		)
		(pad "J7" smd circle
			(at -3.601 -2 270)
			(size 0.45 0.45)
			(layers "F.Cu" "F.Mask" "F.Paste")
			(net 236 "/FPGA MSSIO/MEM.DAT3")
			(pinfunction "MSSIO5B4")
			(pintype "bidirectional")
			(die_length 10.8496)
		)
		(pad "J8" smd circle
			(at -2.8 -2 270)
			(size 0.45 0.45)
			(layers "F.Cu" "F.Mask" "F.Paste")
			(net 417 "GND")
			(pinfunction "VSS")
			(pintype "passive")
		)
		(pad "J9" smd circle
			(at -2 -2 270)
			(size 0.45 0.45)
			(layers "F.Cu" "F.Mask" "F.Paste")
			(net 49 "VDDAUX")
			(pinfunction "VDDAUX1")
			(pintype "passive")
		)
		(pad "J10" smd circle
			(at -1.2 -2 270)
			(size 0.45 0.45)
			(layers "F.Cu" "F.Mask" "F.Paste")
			(net 417 "GND")
			(pinfunction "VSS")
			(pintype "passive")
		)
		(pad "J11" smd circle
			(at -0.401 -2 270)
			(size 0.45 0.45)
			(layers "F.Cu" "F.Mask" "F.Paste")
			(net 50 "+3V3")
			(pinfunction "VDDI3")
			(pintype "passive")
		)
		(pad "J12" smd circle
			(at 0.4 -2 270)
			(size 0.45 0.45)
			(layers "F.Cu" "F.Mask" "F.Paste")
			(net 417 "GND")
			(pinfunction "VSS")
			(pintype "passive")
		)
		(pad "J13" smd circle
			(at 1.199 -2 270)
			(size 0.45 0.45)
			(layers "F.Cu" "F.Mask" "F.Paste")
			(net 49 "VDDAUX")
			(pinfunction "VDDAUX1")
			(pintype "passive")
		)
		(pad "J14" smd circle
			(at 1.999 -2 270)
			(size 0.45 0.45)
			(layers "F.Cu" "F.Mask" "F.Paste")
			(net 417 "GND")
			(pinfunction "VSS")
			(pintype "passive")
		)
		(pad "J15" smd circle
			(at 2.799 -2 270)
			(size 0.45 0.45)
			(layers "F.Cu" "F.Mask" "F.Paste")
			(net 47 "+1V05")
			(pinfunction "VDD")
			(pintype "power_in")
		)
		(pad "J16" smd circle
			(at 3.6 -2 270)
			(size 0.45 0.45)
			(layers "F.Cu" "F.Mask" "F.Paste")
			(net 417 "GND")
			(pinfunction "VSS")
			(pintype "passive")
		)
		(pad "J17" smd circle
			(at 4.4 -2 270)
			(size 0.45 0.45)
			(layers "F.Cu" "F.Mask" "F.Paste")
			(net 418 "+2V5")
			(pinfunction "VDD25")
			(pintype "passive")
		)
		(pad "J18" smd circle
			(at 5.2 -2 270)
			(size 0.45 0.45)
			(layers "F.Cu" "F.Mask" "F.Paste")
			(net 418 "+2V5")
			(pinfunction "VDDA25")
			(pintype "power_in")
		)
		(pad "J19" smd circle
			(at 5.999 -2 270)
			(size 0.45 0.45)
			(layers "F.Cu" "F.Mask" "F.Paste")
			(net 399 "unconnected-(U1H-XCVR_0C_REFCLK_P-PadJ19)")
			(pinfunction "XCVR_0C_REFCLK_P")
			(pintype "input+no_connect")
			(die_length 4.98524)
		)
		(pad "J20" smd circle
			(at 6.799 -2 270)
			(size 0.45 0.45)
			(layers "F.Cu" "F.Mask" "F.Paste")
			(net 400 "unconnected-(U1H-XCVR_0C_REFCLK_N-PadJ20)")
			(pinfunction "XCVR_0C_REFCLK_N")
			(pintype "input+no_connect")
			(die_length 4.97965)
		)
		(pad "J21" smd circle
			(at 7.599 -2 270)
			(size 0.45 0.45)
			(layers "F.Cu" "F.Mask" "F.Paste")
			(net 47 "+1V05")
			(pinfunction "VDDA")
			(pintype "passive")
		)
		(pad "J22" smd circle
			(at 8.4 -2 270)
			(size 0.45 0.45)
			(layers "F.Cu" "F.Mask" "F.Paste")
			(net 417 "GND")
			(pinfunction "VSS")
			(pintype "passive")
		)
		(pad "K1" smd circle
			(at -8.401 -1.2 270)
			(size 0.45 0.45)
			(layers "F.Cu" "F.Mask" "F.Paste")
			(net 389 "/FPGA MSS/LPDDR4.CKE0_A")
			(pinfunction "MSS_DDR_CKE0")
			(pintype "bidirectional")
			(die_length 8.39963)
		)
		(pad "K2" smd circle
			(at -7.6 -1.2 270)
			(size 0.45 0.45)
			(layers "F.Cu" "F.Mask" "F.Paste")
			(net 137 "SD_VDD")
			(pinfunction "VDDI4")
			(pintype "passive")
		)
		(pad "K3" smd circle
			(at -6.8 -1.2 270)
			(size 0.45 0.45)
			(layers "F.Cu" "F.Mask" "F.Paste")
			(net 624 "/FPGA MSSIO/MEM.STRB")
			(pinfunction "MSSIO6B4")
			(pintype "bidirectional")
			(die_length 7.2517)
		)
		(pad "K4" smd circle
			(at -6 -1.2 270)
			(size 0.45 0.45)
			(layers "F.Cu" "F.Mask" "F.Paste")
			(net 261 "/FPGA MSSIO/MEM.DAT2")
			(pinfunction "MSSIO4B4")
			(pintype "bidirectional")
			(die_length 7.47273)
		)
		(pad "K5" smd circle
			(at -5.201 -1.2 270)
			(size 0.45 0.45)
			(layers "F.Cu" "F.Mask" "F.Paste")
			(net 625 "/FPGA MSSIO/MEM.CMD")
			(pinfunction "MSSIO1B4")
			(pintype "bidirectional")
			(die_length 9.04979)
		)
		(pad "K6" smd circle
			(at -4.401 -1.2 270)
			(size 0.45 0.45)
			(layers "F.Cu" "F.Mask" "F.Paste")
			(net 401 "unconnected-(U1F-MSS_SGMII_RXP1-PadK6)")
			(pinfunction "MSS_SGMII_RXP1")
			(pintype "bidirectional+no_connect")
			(die_length 10.8747)
		)
		(pad "K7" smd circle
			(at -3.601 -1.2 270)
			(size 0.45 0.45)
			(layers "F.Cu" "F.Mask" "F.Paste")
			(net 402 "unconnected-(U1F-MSS_SGMII_RXN1-PadK7)")
			(pinfunction "MSS_SGMII_RXN1")
			(pintype "bidirectional+no_connect")
			(die_length 10.9008)
		)
		(pad "K8" smd circle
			(at -2.8 -1.2 270)
			(size 0.45 0.45)
			(layers "F.Cu" "F.Mask" "F.Paste")
			(net 49 "VDDAUX")
			(pinfunction "VDDAUX2")
			(pintype "power_in")
		)
		(pad "K9" smd circle
			(at -2 -1.2 270)
			(size 0.45 0.45)
			(layers "F.Cu" "F.Mask" "F.Paste")
			(net 417 "GND")
			(pinfunction "VSS")
			(pintype "passive")
		)
		(pad "K10" smd circle
			(at -1.2 -1.2 270)
			(size 0.45 0.45)
			(layers "F.Cu" "F.Mask" "F.Paste")
			(net 49 "VDDAUX")
			(pinfunction "VDDAUX1")
			(pintype "passive")
		)
		(pad "K11" smd circle
			(at -0.401 -1.2 270)
			(size 0.45 0.45)
			(layers "F.Cu" "F.Mask" "F.Paste")
			(net 417 "GND")
			(pinfunction "VSS")
			(pintype "passive")
		)
		(pad "K12" smd circle
			(at 0.4 -1.2 270)
			(size 0.45 0.45)
			(layers "F.Cu" "F.Mask" "F.Paste")
			(net 47 "+1V05")
			(pinfunction "VDD")
			(pintype "passive")
		)
		(pad "K13" smd circle
			(at 1.199 -1.2 270)
			(size 0.45 0.45)
			(layers "F.Cu" "F.Mask" "F.Paste")
			(net 417 "GND")
			(pinfunction "VSS")
			(pintype "passive")
		)
		(pad "K14" smd circle
			(at 1.999 -1.2 270)
			(size 0.45 0.45)
			(layers "F.Cu" "F.Mask" "F.Paste")
			(net 47 "+1V05")
			(pinfunction "VDD")
			(pintype "passive")
		)
		(pad "K15" smd circle
			(at 2.799 -1.2 270)
			(size 0.45 0.45)
			(layers "F.Cu" "F.Mask" "F.Paste")
			(net 417 "GND")
			(pinfunction "VSS")
			(pintype "passive")
		)
		(pad "K16" smd circle
			(at 3.6 -1.2 270)
			(size 0.45 0.45)
			(layers "F.Cu" "F.Mask" "F.Paste")
			(net 47 "+1V05")
			(pinfunction "VDD")
			(pintype "passive")
		)
		(pad "K17" smd circle
			(at 4.4 -1.2 270)
			(size 0.45 0.45)
			(layers "F.Cu" "F.Mask" "F.Paste")
			(net 417 "GND")
			(pinfunction "VSS")
			(pintype "passive")
		)
		(pad "K18" smd circle
			(at 5.2 -1.2 270)
			(size 0.45 0.45)
			(layers "F.Cu" "F.Mask" "F.Paste")
			(net 418 "+2V5")
			(pinfunction "VDD_XCVR_CLK")
			(pintype "power_in")
		)
		(pad "K19" smd circle
			(at 5.999 -1.2 270)
			(size 0.45 0.45)
			(layers "F.Cu" "F.Mask" "F.Paste")
			(net 47 "+1V05")
			(pinfunction "VDDA")
			(pintype "passive")
		)
		(pad "K20" smd circle
			(at 6.799 -1.2 270)
			(size 0.45 0.45)
			(layers "F.Cu" "F.Mask" "F.Paste")
			(net 417 "GND")
			(pinfunction "VSS")
			(pintype "passive")
		)
		(pad "K21" smd circle
			(at 7.599 -1.2 270)
			(size 0.45 0.45)
			(layers "F.Cu" "F.Mask" "F.Paste")
			(net 138 "/Bottom Connector/PCIE.RXD1_N")
			(pinfunction "XCVR_0_RX1_N")
			(pintype "input")
			(die_length 5.26367)
		)
		(pad "K22" smd circle
			(at 8.4 -1.2 270)
			(size 0.45 0.45)
			(layers "F.Cu" "F.Mask" "F.Paste")
			(net 121 "/Bottom Connector/PCIE.RXD1_P")
			(pinfunction "XCVR_0_RX1_P")
			(pintype "input")
			(die_length 5.25117)
		)
		(pad "L1" smd circle
			(at -8.401 -0.401 270)
			(size 0.45 0.45)
			(layers "F.Cu" "F.Mask" "F.Paste")
			(net 393 "/FPGA MSS/LPDDR4.ODT_CA_A")
			(pinfunction "MSS_DDR_ODT0")
			(pintype "bidirectional")
			(die_length 7.44348)
		)
		(pad "L2" smd circle
			(at -7.6 -0.401 270)
			(size 0.45 0.45)
			(layers "F.Cu" "F.Mask" "F.Paste")
			(net 394 "/FPGA MSS/LPDDR4.RESET_n")
			(pinfunction "MSS_DDR_RAM_RST_N/DDR_PLL0_OUT1")
			(pintype "bidirectional")
			(die_length 6.88475)
		)
		(pad "L3" smd circle
			(at -6.8 -0.401 270)
			(size 0.45 0.45)
			(layers "F.Cu" "F.Mask" "F.Paste")
			(net 395 "/FPGA MSS/LPDDR4.CS0_A")
			(pinfunction "MSS_DDR_CS0")
			(pintype "bidirectional")
			(die_length 7.35905)
		)
		(pad "L4" smd circle
			(at -6 -0.401 270)
			(size 0.45 0.45)
			(layers "F.Cu" "F.Mask" "F.Paste")
			(net 417 "GND")
			(pinfunction "VSS")
			(pintype "passive")
		)
		(pad "L5" smd circle
			(at -5.201 -0.401 270)
			(size 0.45 0.45)
			(layers "F.Cu" "F.Mask" "F.Paste")
			(net 42 "/Ethernet/SGMII.RX0_P")
			(pinfunction "MSS_SGMII_RXP0")
			(pintype "bidirectional")
			(die_length 9.80775)
		)
		(pad "L6" smd circle
			(at -4.401 -0.401 270)
			(size 0.45 0.45)
			(layers "F.Cu" "F.Mask" "F.Paste")
			(net 41 "/Ethernet/SGMII.RX0_N")
			(pinfunction "MSS_SGMII_RXN0")
			(pintype "bidirectional")
			(die_length 9.80095)
		)
		(pad "L7" smd circle
			(at -3.601 -0.401 270)
			(size 0.45 0.45)
			(layers "F.Cu" "F.Mask" "F.Paste")
			(net 10 "MSS_REFCLK_P")
			(pinfunction "MSS_REFCLK_IN_P")
			(pintype "bidirectional")
			(die_length 10.0914)
		)
		(pad "L8" smd circle
			(at -2.8 -0.401 270)
			(size 0.45 0.45)
			(layers "F.Cu" "F.Mask" "F.Paste")
			(net 9 "MSS_REFCLK_N")
			(pinfunction "MSS_REFCLK_IN_N")
			(pintype "bidirectional")
			(die_length 10.0825)
		)
		(pad "L9" smd circle
			(at -2 -0.401 270)
			(size 0.45 0.45)
			(layers "F.Cu" "F.Mask" "F.Paste")
			(net 49 "VDDAUX")
			(pinfunction "VDDAUX2")
			(pintype "passive")
		)
		(pad "L10" smd circle
			(at -1.2 -0.401 270)
			(size 0.45 0.45)
			(layers "F.Cu" "F.Mask" "F.Paste")
			(net 417 "GND")
			(pinfunction "VSS")
			(pintype "passive")
		)
		(pad "L11" smd circle
			(at -0.401 -0.401 270)
			(size 0.45 0.45)
			(layers "F.Cu" "F.Mask" "F.Paste")
			(net 47 "+1V05")
			(pinfunction "VDD")
			(pintype "passive")
		)
		(pad "L12" smd circle
			(at 0.4 -0.401 270)
			(size 0.45 0.45)
			(layers "F.Cu" "F.Mask" "F.Paste")
			(net 417 "GND")
			(pinfunction "VSS")
			(pintype "passive")
		)
		(pad "L13" smd circle
			(at 1.199 -0.401 270)
			(size 0.45 0.45)
			(layers "F.Cu" "F.Mask" "F.Paste")
			(net 47 "+1V05")
			(pinfunction "VDD")
			(pintype "passive")
		)
		(pad "L14" smd circle
			(at 1.999 -0.401 270)
			(size 0.45 0.45)
			(layers "F.Cu" "F.Mask" "F.Paste")
			(net 417 "GND")
			(pinfunction "VSS")
			(pintype "passive")
		)
		(pad "L15" smd circle
			(at 2.799 -0.401 270)
			(size 0.45 0.45)
			(layers "F.Cu" "F.Mask" "F.Paste")
			(net 418 "+2V5")
			(pinfunction "VDD25")
			(pintype "passive")
		)
		(pad "L16" smd circle
			(at 3.6 -0.401 270)
			(size 0.45 0.45)
			(layers "F.Cu" "F.Mask" "F.Paste")
			(net 417 "GND")
			(pinfunction "VSS")
			(pintype "passive")
		)
		(pad "L17" smd circle
			(at 4.4 -0.401 270)
			(size 0.45 0.45)
			(layers "F.Cu" "F.Mask" "F.Paste")
			(net 47 "+1V05")
			(pinfunction "VDD")
			(pintype "passive")
		)
		(pad "L18" smd circle
			(at 5.2 -0.401 270)
			(size 0.45 0.45)
			(layers "F.Cu" "F.Mask" "F.Paste")
			(net 417 "GND")
			(pinfunction "VSS")
			(pintype "passive")
		)
	)
)
